# BASEBOARD_FAB2 (Tioga Pass) — schematic netlist excerpt (pin names and nets, part order shuffled) for the footprints in the layout excerpt that follows; sources: Cadence DE-HDL packaged netlist, KiCad conversion of Wiwynn_Tioga_Pass_MB.brd

R6W22  RES  20.0 1% CHIP  pkg 0402  page 247 : A = SMB_HOST_STBY_LVC3_SCL ; B = SMB_HOST_STBY_LVC3_SCL_R3
C8F3  CAP  3300PF 50V 10% EMPTY  pkg 0402LF  page 240 : A = VR_P3V3_STBY_PHASE ; B = VR_P3V3_STBY_SNUB
C2T19  CAP_A  1.0UF 6.3V 10% X6S  pkg 0402V  page 101 : A = P3V3_STBY_MNG_CPU ; B = GND

(kicad_pcb
	(version 20260206)
	(generator "pcbnew")
	(generator_version "10.0")
	(general
		(thickness 1.6)
		(legacy_teardrops no)
	)
	(paper "A4")
	(title_block
		(title "Wiwynn_Tioga_Pass_MB.brd")
		(comment 1 "Tioga Pass / footprints 2896-2898 of 4770")
	)
	(layers
		(0 "F.Cu" signal "TOP")
		(4 "In1.Cu" signal "L2GND")
		(6 "In2.Cu" signal "L3")
		(8 "In3.Cu" signal "L4GND")
		(10 "In4.Cu" signal "L5")
		(12 "In5.Cu" signal "L6GND")
		(14 "In6.Cu" signal "L7VCC")
		(16 "In7.Cu" signal "L8VCC")
		(18 "In8.Cu" signal "L9GND")
		(20 "In9.Cu" signal "L10")
		(22 "In10.Cu" signal "L11GND")
		(24 "In11.Cu" signal "L12")
		(26 "In12.Cu" signal "L13GND")
		(2 "B.Cu" signal "BOTTOM")
		(9 "F.Adhes" user "F.Adhesive")
		(11 "B.Adhes" user "B.Adhesive")
		(13 "F.Paste" user "Package Geometry/Pastemask Top")
		(15 "B.Paste" user "Package Geometry/Pastemask Bottom")
		(5 "F.SilkS" user "Ref Des/Silkscreen Top")
		(7 "B.SilkS" user "Ref Des/Silkscreen Bottom")
		(1 "F.Mask" user "Board Geometry/Soldermask Top")
		(3 "B.Mask" user "Board Geometry/Soldermask Bottom")
		(17 "Dwgs.User" user "User.Drawings")
		(19 "Cmts.User" user "User.Comments")
		(21 "Eco1.User" user "User.Eco1")
		(23 "Eco2.User" user "User.Eco2")
		(25 "Edge.Cuts" user "Board Geometry/Outline")
		(27 "Margin" user)
		(31 "F.CrtYd" user "Package Geometry/Place Bound Top")
		(29 "B.CrtYd" user "Package Geometry/Place Bound Bottom")
		(35 "F.Fab" user "Ref Des/Assembly Top")
		(33 "B.Fab" user "Ref Des/Assembly Bottom")
	)
	(footprint ""
		(layer "B.Cu")
		(at 480.00666 -27.70632 180)
		(property "Reference" "C2T19"
			(at 0 0 0)
			(layer "B.SilkS")
			(hide yes)
			(effects
				(font
					(size 1.27 1.27)
				)
				(justify mirror)
			)
		)
		(property "Value" ""
			(at 0 0 0)
			(layer "B.Fab")
			(effects
				(font
					(size 1.27 1.27)
				)
				(justify mirror)
			)
		)
		(duplicate_pad_numbers_are_jumpers no)
		(fp_poly
			(pts
				(xy -0.3048 -0.1016) (xy -0.3048 0.9906) (xy 0.3048 0.9906) (xy 0.3048 -0.1016)
			)
			(stroke
				(width 0)
				(type default)
			)
			(fill no)
			(layer "B.CrtYd")
		)
		(fp_line
			(start 0.3048 0.9906)
			(end -0.3048 0.9906)
			(stroke
				(width 0.1)
				(type default)
			)
			(layer "B.Fab")
		)
		(fp_line
			(start 0.3048 -0.1016)
			(end 0.3048 0.9906)
			(stroke
				(width 0.1)
				(type default)
			)
			(layer "B.Fab")
		)
		(fp_line
			(start -0.3048 0.9906)
			(end -0.3048 -0.1016)
			(stroke
				(width 0.1)
				(type default)
			)
			(layer "B.Fab")
		)
		(fp_line
			(start -0.3048 -0.1016)
			(end 0.3048 -0.1016)
			(stroke
				(width 0.1)
				(type default)
			)
			(layer "B.Fab")
		)
		(pad "1" smd rect
			(at 0 0)
			(size 0.508 0.508)
			(layers "B.Cu" "B.Mask" "B.Paste")
			(net "P3V3_STBY_MNG_CPU")
		)
		(pad "2" smd rect
			(at 0 0.889)
			(size 0.508 0.508)
			(layers "B.Cu" "B.Mask" "B.Paste")
			(net "GND")
		)
		(zone
			(layer "B.Cu")
			(hatch none 0.5)
			(connect_pads
				(clearance 0)
			)
			(min_thickness 0.25)
			(keepout
				(tracks not_allowed)
				(vias allowed)
				(pads allowed)
				(copperpour not_allowed)
				(footprints allowed)
			)
			(placement
				(enabled no)
				(sheetname "")
			)
			(fill
				(thermal_gap 0.5)
				(thermal_bridge_width 0.5)
				(island_removal_mode 0)
			)
			(polygon
				(pts
					(xy 479.75266 -28.34132) (xy 480.26066 -28.34132) (xy 480.26066 -27.96032) (xy 479.75266 -27.96032)
				)
			)
		)
		(zone
			(layer "B.Cu")
			(hatch none 0.5)
			(connect_pads
				(clearance 0)
			)
			(min_thickness 0.25)
			(keepout
				(tracks allowed)
				(vias not_allowed)
				(pads allowed)
				(copperpour not_allowed)
				(footprints allowed)
			)
			(placement
				(enabled no)
				(sheetname "")
			)
			(fill
				(thermal_gap 0.5)
				(thermal_bridge_width 0.5)
				(island_removal_mode 0)
			)
			(polygon
				(pts
					(xy 479.75266 -27.96032) (xy 480.26066 -27.96032) (xy 480.26066 -28.34132) (xy 479.75266 -28.34132)
				)
			)
		)
	)
	(footprint ""
		(layer "B.Cu")
		(at 473.084906 -19.085052 90)
		(property "Reference" "C8F3"
			(at 0 0 90)
			(layer "B.SilkS")
			(hide yes)
			(effects
				(font
					(size 1.27 1.27)
				)
				(justify mirror)
			)
		)
		(property "Value" ""
			(at 0 0 90)
			(layer "B.Fab")
			(effects
				(font
					(size 1.27 1.27)
				)
				(justify mirror)
			)
		)
		(duplicate_pad_numbers_are_jumpers no)
		(fp_rect
			(start -0.3048 -0.1016)
			(end 0.3048 0.9906)
			(stroke
				(width 0)
				(type default)
			)
			(fill no)
			(layer "B.CrtYd")
		)
		(fp_line
			(start 0.3048 -0.1016)
			(end 0.3048 0.9906)
			(stroke
				(width 0.1)
				(type default)
			)
			(layer "B.Fab")
		)
		(fp_line
			(start -0.3048 -0.1016)
			(end 0.3048 -0.1016)
			(stroke
				(width 0.1)
				(type default)
			)
			(layer "B.Fab")
		)
		(fp_line
			(start 0.3048 0.9906)
			(end -0.3048 0.9906)
			(stroke
				(width 0.1)
				(type default)
			)
			(layer "B.Fab")
		)
		(fp_line
			(start -0.3048 0.9906)
			(end -0.3048 -0.1016)
			(stroke
				(width 0.1)
				(type default)
			)
			(layer "B.Fab")
		)
		(pad "1" smd rect
			(at 0 0 270)
			(size 0.508 0.508)
			(layers "B.Cu" "B.Mask" "B.Paste")
			(net "VR_P3V3_STBY_PHASE")
		)
		(pad "2" smd rect
			(at 0 0.889 270)
			(size 0.508 0.508)
			(layers "B.Cu" "B.Mask" "B.Paste")
			(net "VR_P3V3_STBY_SNUB")
		)
		(zone
			(layer "B.Cu")
			(hatch none 0.5)
			(connect_pads
				(clearance 0)
			)
			(min_thickness 0.25)
			(keepout
				(tracks not_allowed)
				(vias allowed)
				(pads allowed)
				(copperpour not_allowed)
				(footprints allowed)
			)
			(placement
				(enabled no)
				(sheetname "")
			)
			(fill
				(thermal_gap 0.5)
				(thermal_bridge_width 0.5)
				(island_removal_mode 0)
			)
			(polygon
				(pts
					(xy 473.338906 -18.831052) (xy 473.719906 -18.831052) (xy 473.719906 -19.339052) (xy 473.338906 -19.339052)
				)
			)
		)
		(zone
			(layer "B.Cu")
			(hatch none 0.5)
			(connect_pads
				(clearance 0)
			)
			(min_thickness 0.25)
			(keepout
				(tracks allowed)
				(vias not_allowed)
				(pads allowed)
				(copperpour not_allowed)
				(footprints allowed)
			)
			(placement
				(enabled no)
				(sheetname "")
			)
			(fill
				(thermal_gap 0.5)
				(thermal_bridge_width 0.5)
				(island_removal_mode 0)
			)
			(polygon
				(pts
					(xy 473.338906 -18.831052) (xy 473.719906 -18.831052) (xy 473.719906 -19.339052) (xy 473.338906 -19.339052)
				)
			)
		)
	)
	(footprint ""
		(layer "B.Cu")
		(at 449.6435 -24.003 90)
		(property "Reference" "R6W22"
			(at 0.8382 -0.67818 90)
			(unlocked yes)
			(layer "B.SilkS")
			(effects
				(font
					(size 0.4064 0.254)
					(thickness 0.1524)
				)
				(justify left mirror)
			)
		)
		(property "Value" ""
			(at 0 0 90)
			(layer "B.Fab")
			(effects
				(font
					(size 1.27 1.27)
				)
				(justify mirror)
			)
		)
		(duplicate_pad_numbers_are_jumpers no)
		(fp_poly
			(pts
				(xy 0.2794 -0.1016) (xy -0.2794 -0.1016) (xy -0.2794 0.9906) (xy 0.2794 0.9906)
			)
			(stroke
				(width 0)
				(type default)
			)
			(fill no)
			(layer "B.CrtYd")
		)
		(fp_line
			(start 0.2794 -0.1016)
			(end 0.2794 0.9906)
			(stroke
				(width 0.1)
				(type default)
			)
			(layer "B.Fab")
		)
		(fp_line
			(start -0.2794 -0.1016)
			(end 0.2794 -0.1016)
			(stroke
				(width 0.1)
				(type default)
			)
			(layer "B.Fab")
		)
		(fp_line
			(start 0.2794 0.9906)
			(end -0.2794 0.9906)
			(stroke
				(width 0.1)
				(type default)
			)
			(layer "B.Fab")
		)
		(fp_line
			(start -0.2794 0.9906)
			(end -0.2794 -0.1016)
			(stroke
				(width 0.1)
				(type default)
			)
			(layer "B.Fab")
		)
		(pad "1" smd rect
			(at 0 0 270)
			(size 0.508 0.508)
			(layers "B.Cu" "B.Mask" "B.Paste")
			(net "SMB_HOST_STBY_LVC3_SCL")
		)
		(pad "2" smd rect
			(at 0 0.889 270)
			(size 0.508 0.508)
			(layers "B.Cu" "B.Mask" "B.Paste")
			(net "SMB_HOST_STBY_LVC3_SCL_R3")
		)
		(zone
			(layer "B.Cu")
			(hatch none 0.5)
			(connect_pads
				(clearance 0)
			)
			(min_thickness 0.25)
			(keepout
				(tracks allowed)
				(vias not_allowed)
				(pads allowed)
				(copperpour not_allowed)
				(footprints allowed)
			)
			(placement
				(enabled no)
				(sheetname "")
			)
			(fill
				(thermal_gap 0.5)
				(thermal_bridge_width 0.5)
				(island_removal_mode 0)
			)
			(polygon
				(pts
					(xy 449.8975 -24.257) (xy 449.8975 -23.749) (xy 450.2785 -23.749) (xy 450.2785 -24.257)
				)
			)
		)
		(zone
			(layer "B.Cu")
			(hatch none 0.5)
			(connect_pads
				(clearance 0)
			)
			(min_thickness 0.25)
			(keepout
				(tracks not_allowed)
				(vias allowed)
				(pads allowed)
				(copperpour not_allowed)
				(footprints allowed)
			)
			(placement
				(enabled no)
				(sheetname "")
			)
			(fill
				(thermal_gap 0.5)
				(thermal_bridge_width 0.5)
				(island_removal_mode 0)
			)
			(polygon
				(pts
					(xy 450.2785 -24.257) (xy 450.2785 -23.749) (xy 449.8975 -23.749) (xy 449.8975 -24.257)
				)
			)
		)
	)
)
